(kicad_pcb
	(version 20260206)
	(generator "pcbnew")
	(generator_version "10.0")
	(general
		(thickness 1.6)
		(legacy_teardrops no)
	)
	(paper "A4")
	(title_block
		(title "04192023_DAF0TMB3IC0_F0TG_MB_C_brd_V02_OCP.brd")
		(comment 1 "Grand Teton / footprint 2783 of 8354 (U26), pads 1200-1313 of 6102")
	)
	(layers
		(0 "F.Cu" signal "TOP")
		(4 "In1.Cu" signal "GND")
		(6 "In2.Cu" signal "IN1")
		(8 "In3.Cu" signal "GND1")
		(10 "In4.Cu" signal "IN2")
		(12 "In5.Cu" signal "GND2")
		(14 "In6.Cu" signal "IN3")
		(16 "In7.Cu" signal "GND3")
		(18 "In8.Cu" signal "VCC")
		(20 "In9.Cu" signal "VCC1")
		(22 "In10.Cu" signal "GND4")
		(24 "In11.Cu" signal "IN4")
		(26 "In12.Cu" signal "GND5")
		(28 "In13.Cu" signal "IN5")
		(30 "In14.Cu" signal "GND6")
		(32 "In15.Cu" signal "IN6")
		(34 "In16.Cu" signal "GND7")
		(2 "B.Cu" signal "BOTTOM")
		(9 "F.Adhes" user "F.Adhesive")
		(11 "B.Adhes" user "B.Adhesive")
		(13 "F.Paste" user "Package Geometry/Pastemask Top")
		(15 "B.Paste" user "Package Geometry/Pastemask Bottom")
		(5 "F.SilkS" user "Ref Des/Silkscreen Top")
		(7 "B.SilkS" user "Ref Des/Silkscreen Bottom")
		(1 "F.Mask" user "Board Geometry/Soldermask Top")
		(3 "B.Mask" user "Board Geometry/Soldermask Bottom")
		(17 "Dwgs.User" user "User.Drawings")
		(19 "Cmts.User" user "User.Comments")
		(21 "Eco1.User" user "User.Eco1")
		(23 "Eco2.User" user "User.Eco2")
		(25 "Edge.Cuts" user "Board Geometry/Outline")
		(27 "Margin" user)
		(31 "F.CrtYd" user "Package Geometry/Place Bound Top")
		(29 "B.CrtYd" user "Package Geometry/Place Bound Bottom")
		(35 "F.Fab" user "Ref Des/Assembly Top")
		(33 "B.Fab" user "Ref Des/Assembly Bottom")
	)
	(footprint ""
		(layer "F.Cu")
		(at 111.927894 -258.880356 180)
		(property "Reference" "U26"
			(at -45.05579 -61.794136 0)
			(unlocked yes)
			(layer "F.SilkS")
			(effects
				(font
					(size 0.7874 0.5842)
					(thickness 0.1524)
				)
			)
		)
		(property "Value" ""
			(at 0 0 180)
			(layer "F.Fab")
			(effects
				(font
					(size 1.27 1.27)
				)
			)
		)
		(duplicate_pad_numbers_are_jumpers no)
		(pad "AT60" smd circle
			(at 20.830032 -8.459978 180)
			(size 0.450088 0.450088)
			(layers "F.Cu" "F.Mask" "F.Paste")
			(net "GND")
		)
		(pad "AT61" smd circle
			(at 21.770086 -8.459978 180)
			(size 0.450088 0.450088)
			(layers "F.Cu" "F.Mask" "F.Paste")
			(net "GND")
		)
		(pad "AT62" smd circle
			(at 22.709886 -8.459978 180)
			(size 0.450088 0.450088)
			(layers "F.Cu" "F.Mask" "F.Paste")
			(net "M_B_CPU1_ALERT_R_N")
		)
		(pad "AT63" smd circle
			(at 23.64994 -8.459978 180)
			(size 0.450088 0.450088)
			(layers "F.Cu" "F.Mask" "F.Paste")
			(net "GND")
		)
		(pad "AT64" smd circle
			(at 24.589994 -8.459978 180)
			(size 0.450088 0.450088)
			(layers "F.Cu" "F.Mask" "F.Paste")
			(net "GND")
		)
		(pad "AT65" smd circle
			(at 25.530048 -8.459978 180)
			(size 0.450088 0.450088)
			(layers "F.Cu" "F.Mask" "F.Paste")
			(net "M_F_CPU1_ALERT_R_N")
		)
		(pad "AT66" smd circle
			(at 26.470102 -8.459978 180)
			(size 0.450088 0.450088)
			(layers "F.Cu" "F.Mask" "F.Paste")
			(net "GND")
		)
		(pad "AT67" smd circle
			(at 27.409902 -8.459978 180)
			(size 0.450088 0.450088)
			(layers "F.Cu" "F.Mask" "F.Paste")
			(net "GND")
		)
		(pad "AT68" smd circle
			(at 28.349956 -8.459978 180)
			(size 0.450088 0.450088)
			(layers "F.Cu" "F.Mask" "F.Paste")
			(net "GND")
		)
		(pad "AT69" smd circle
			(at 29.29001 -8.459978 180)
			(size 0.450088 0.450088)
			(layers "F.Cu" "F.Mask" "F.Paste")
			(net "M_E_CPU1_ALERT_R_N")
		)
		(pad "AT70" smd circle
			(at 30.230064 -8.459978 180)
			(size 0.450088 0.450088)
			(layers "F.Cu" "F.Mask" "F.Paste")
			(net "GND")
		)
		(pad "AT71" smd circle
			(at 31.170118 -8.459978 180)
			(size 0.450088 0.450088)
			(layers "F.Cu" "F.Mask" "F.Paste")
			(net "GND")
		)
		(pad "AT72" smd circle
			(at 32.109918 -8.459978 180)
			(size 0.450088 0.450088)
			(layers "F.Cu" "F.Mask" "F.Paste")
			(net "GND")
		)
		(pad "AT73" smd circle
			(at 33.049972 -8.459978 180)
			(size 0.450088 0.450088)
			(layers "F.Cu" "F.Mask" "F.Paste")
			(net "GND")
		)
		(pad "AT74" smd circle
			(at 33.990026 -8.459978 180)
			(size 0.450088 0.450088)
			(layers "F.Cu" "F.Mask" "F.Paste")
			(net "M_A_CPU1_RESET_N")
		)
		(pad "AU1" smd circle
			(at -34.159952 -7.649972 180)
			(size 0.450088 0.450088)
			(layers "F.Cu" "F.Mask" "F.Paste")
			(net "GND")
		)
		(pad "AU2" smd circle
			(at -33.219898 -7.649972 180)
			(size 0.450088 0.450088)
			(layers "F.Cu" "F.Mask" "F.Paste")
			(net "M_G_CPU1_SA_CS_N<0>")
		)
		(pad "AU3" smd circle
			(at -32.280098 -7.649972 180)
			(size 0.450088 0.450088)
			(layers "F.Cu" "F.Mask" "F.Paste")
			(net "GND")
		)
		(pad "AU4" smd circle
			(at -31.340044 -7.649972 180)
			(size 0.450088 0.450088)
			(layers "F.Cu" "F.Mask" "F.Paste")
			(net "GND")
		)
		(pad "AU5" smd circle
			(at -30.39999 -7.649972 180)
			(size 0.450088 0.450088)
			(layers "F.Cu" "F.Mask" "F.Paste")
			(net "M_K_CPU1_SA_CS_N<0>")
		)
		(pad "AU6" smd circle
			(at -29.459936 -7.649972 180)
			(size 0.450088 0.450088)
			(layers "F.Cu" "F.Mask" "F.Paste")
			(net "GND")
		)
		(pad "AU7" smd circle
			(at -28.519882 -7.649972 180)
			(size 0.450088 0.450088)
			(layers "F.Cu" "F.Mask" "F.Paste")
			(net "M_K_CPU1_RESET_N")
		)
		(pad "AU8" smd circle
			(at -27.580082 -7.649972 180)
			(size 0.450088 0.450088)
			(layers "F.Cu" "F.Mask" "F.Paste")
			(net "GND")
		)
		(pad "AU9" smd circle
			(at -26.640028 -7.649972 180)
			(size 0.450088 0.450088)
			(layers "F.Cu" "F.Mask" "F.Paste")
			(net "M_L_CPU1_SA_CS_N<0>")
		)
		(pad "AU10" smd circle
			(at -25.699974 -7.649972 180)
			(size 0.450088 0.450088)
			(layers "F.Cu" "F.Mask" "F.Paste")
			(net "M_L_CPU1_RESET_N")
		)
		(pad "AU11" smd circle
			(at -24.75992 -7.649972 180)
			(size 0.450088 0.450088)
			(layers "F.Cu" "F.Mask" "F.Paste")
			(net "GND")
		)
		(pad "AU12" smd circle
			(at -23.82012 -7.649972 180)
			(size 0.450088 0.450088)
			(layers "F.Cu" "F.Mask" "F.Paste")
			(net "M_H_CPU1_SA_CS_N<0>")
		)
		(pad "AU13" smd circle
			(at -22.880066 -7.649972 180)
			(size 0.450088 0.450088)
			(layers "F.Cu" "F.Mask" "F.Paste")
			(net "GND")
		)
		(pad "AU14" smd circle
			(at -21.940012 -7.649972 180)
			(size 0.450088 0.450088)
			(layers "F.Cu" "F.Mask" "F.Paste")
			(net "M_H_CPU1_RESET_N")
		)
		(pad "AU15" smd circle
			(at -20.999958 -7.649972 180)
			(size 0.450088 0.450088)
			(layers "F.Cu" "F.Mask" "F.Paste")
			(net "GND")
		)
		(pad "AU16" smd circle
			(at -20.059904 -7.649972 180)
			(size 0.450088 0.450088)
			(layers "F.Cu" "F.Mask" "F.Paste")
			(net "M_J_CPU1_SA_CS_N<0>")
		)
		(pad "AU17" smd circle
			(at -19.120104 -7.649972 180)
			(size 0.450088 0.450088)
			(layers "F.Cu" "F.Mask" "F.Paste")
			(net "M_J_CPU1_RESET_N")
		)
		(pad "AU18" smd circle
			(at -18.18005 -7.649972 180)
			(size 0.450088 0.450088)
			(layers "F.Cu" "F.Mask" "F.Paste")
			(net "GND")
		)
		(pad "AU19" smd circle
			(at -17.239996 -7.649972 180)
			(size 0.450088 0.450088)
			(layers "F.Cu" "F.Mask" "F.Paste")
			(net "M_I_CPU1_SA_CS_N<0>")
		)
		(pad "AU20" smd circle
			(at -16.299942 -7.649972 180)
			(size 0.450088 0.450088)
			(layers "F.Cu" "F.Mask" "F.Paste")
			(net "GND")
		)
		(pad "AU21" smd circle
			(at -15.359888 -7.649972 180)
			(size 0.450088 0.450088)
			(layers "F.Cu" "F.Mask" "F.Paste")
			(net "M_I_CPU1_RESET_N")
		)
		(pad "AU22" smd circle
			(at -14.420088 -7.649972 180)
			(size 0.450088 0.450088)
			(layers "F.Cu" "F.Mask" "F.Paste")
			(net "GND")
		)
		(pad "AU23" smd circle
			(at -13.480034 -7.649972 180)
			(size 0.450088 0.450088)
			(layers "F.Cu" "F.Mask" "F.Paste")
			(net "PVDDCR_SOC_P1")
		)
		(pad "AU24" smd circle
			(at -12.53998 -7.649972 180)
			(size 0.450088 0.450088)
			(layers "F.Cu" "F.Mask" "F.Paste")
			(net "GND")
		)
		(pad "AU25" smd circle
			(at -11.599926 -7.649972 180)
			(size 0.450088 0.450088)
			(layers "F.Cu" "F.Mask" "F.Paste")
			(net "PVDDCR_CPU0_P1")
		)
		(pad "AU26" smd circle
			(at -10.659872 -7.649972 180)
			(size 0.450088 0.450088)
			(layers "F.Cu" "F.Mask" "F.Paste")
			(net "GND")
		)
		(pad "AU27" smd circle
			(at -9.720072 -7.649972 180)
			(size 0.450088 0.450088)
			(layers "F.Cu" "F.Mask" "F.Paste")
			(net "PVDDCR_SOC_P1")
		)
		(pad "AU28" smd circle
			(at -8.780018 -7.649972 180)
			(size 0.450088 0.450088)
			(layers "F.Cu" "F.Mask" "F.Paste")
			(net "GND")
		)
		(pad "AU29" smd circle
			(at -7.839964 -7.649972 180)
			(size 0.450088 0.450088)
			(layers "F.Cu" "F.Mask" "F.Paste")
			(net "PVDDCR_CPU0_P1")
		)
		(pad "AU30" smd circle
			(at -6.89991 -7.649972 180)
			(size 0.450088 0.450088)
			(layers "F.Cu" "F.Mask" "F.Paste")
			(net "GND")
		)
		(pad "AU31" smd circle
			(at -5.96011 -7.649972 180)
			(size 0.450088 0.450088)
			(layers "F.Cu" "F.Mask" "F.Paste")
			(net "PVDDCR_SOC_P1")
		)
		(pad "AU32" smd circle
			(at -5.020056 -7.649972 180)
			(size 0.450088 0.450088)
			(layers "F.Cu" "F.Mask" "F.Paste")
			(net "GND")
		)
		(pad "AU33" smd circle
			(at -4.080002 -7.649972 180)
			(size 0.450088 0.450088)
			(layers "F.Cu" "F.Mask" "F.Paste")
			(net "PVDDCR_CPU0_P1")
		)
		(pad "AU34" smd circle
			(at -3.139948 -7.649972 180)
			(size 0.450088 0.450088)
			(layers "F.Cu" "F.Mask" "F.Paste")
			(net "GND")
		)
		(pad "AU35" smd circle
			(at -2.199894 -7.649972 180)
			(size 0.450088 0.450088)
			(layers "F.Cu" "F.Mask" "F.Paste")
			(net "PVDDCR_SOC_P1")
		)
		(pad "AU36" smd circle
			(at -1.260094 -7.649972 180)
			(size 0.450088 0.450088)
			(layers "F.Cu" "F.Mask" "F.Paste")
			(net "GND")
		)
		(pad "AU40" smd circle
			(at 1.560068 -7.649972 180)
			(size 0.450088 0.450088)
			(layers "F.Cu" "F.Mask" "F.Paste")
			(net "PVDDCR_SOC_P1")
		)
		(pad "AU41" smd circle
			(at 2.500122 -7.649972 180)
			(size 0.450088 0.450088)
			(layers "F.Cu" "F.Mask" "F.Paste")
			(net "GND")
		)
		(pad "AU42" smd circle
			(at 3.439922 -7.649972 180)
			(size 0.450088 0.450088)
			(layers "F.Cu" "F.Mask" "F.Paste")
			(net "PVDDCR_CPU0_P1")
		)
		(pad "AU43" smd circle
			(at 4.379976 -7.649972 180)
			(size 0.450088 0.450088)
			(layers "F.Cu" "F.Mask" "F.Paste")
			(net "GND")
		)
		(pad "AU44" smd circle
			(at 5.32003 -7.649972 180)
			(size 0.450088 0.450088)
			(layers "F.Cu" "F.Mask" "F.Paste")
			(net "PVDDCR_CPU0_P1")
		)
		(pad "AU45" smd circle
			(at 6.260084 -7.649972 180)
			(size 0.450088 0.450088)
			(layers "F.Cu" "F.Mask" "F.Paste")
			(net "GND")
		)
		(pad "AU46" smd circle
			(at 7.199884 -7.649972 180)
			(size 0.450088 0.450088)
			(layers "F.Cu" "F.Mask" "F.Paste")
			(net "PVDDCR_CPU0_P1")
		)
		(pad "AU47" smd circle
			(at 8.139938 -7.649972 180)
			(size 0.450088 0.450088)
			(layers "F.Cu" "F.Mask" "F.Paste")
			(net "GND")
		)
		(pad "AU48" smd circle
			(at 9.079992 -7.649972 180)
			(size 0.450088 0.450088)
			(layers "F.Cu" "F.Mask" "F.Paste")
			(net "PVDDCR_CPU0_P1")
		)
		(pad "AU49" smd circle
			(at 10.020046 -7.649972 180)
			(size 0.450088 0.450088)
			(layers "F.Cu" "F.Mask" "F.Paste")
			(net "GND")
		)
		(pad "AU50" smd circle
			(at 10.9601 -7.649972 180)
			(size 0.450088 0.450088)
			(layers "F.Cu" "F.Mask" "F.Paste")
			(net "PVDD18_S5_P1")
		)
		(pad "AU51" smd circle
			(at 11.8999 -7.649972 180)
			(size 0.450088 0.450088)
			(layers "F.Cu" "F.Mask" "F.Paste")
			(net "GND")
		)
		(pad "AU52" smd circle
			(at 12.839954 -7.649972 180)
			(size 0.450088 0.450088)
			(layers "F.Cu" "F.Mask" "F.Paste")
			(net "PVDD18_S5_P1")
		)
		(pad "AU53" smd circle
			(at 13.780008 -7.649972 180)
			(size 0.450088 0.450088)
			(layers "F.Cu" "F.Mask" "F.Paste")
			(net "GND")
		)
		(pad "AU54" smd circle
			(at 14.720062 -7.649972 180)
			(size 0.450088 0.450088)
			(layers "F.Cu" "F.Mask" "F.Paste")
			(net "PVDD18_S5_P1")
		)
		(pad "AU55" smd circle
			(at 15.660116 -7.649972 180)
			(size 0.450088 0.450088)
			(layers "F.Cu" "F.Mask" "F.Paste")
			(net "M_C_CPU1_RESET_N")
		)
		(pad "AU56" smd circle
			(at 16.599916 -7.649972 180)
			(size 0.450088 0.450088)
			(layers "F.Cu" "F.Mask" "F.Paste")
			(net "GND")
		)
		(pad "AU57" smd circle
			(at 17.53997 -7.649972 180)
			(size 0.450088 0.450088)
			(layers "F.Cu" "F.Mask" "F.Paste")
			(net "Net_2008")
		)
		(pad "AU58" smd circle
			(at 18.480024 -7.649972 180)
			(size 0.450088 0.450088)
			(layers "F.Cu" "F.Mask" "F.Paste")
			(net "GND")
		)
		(pad "AU59" smd circle
			(at 19.420078 -7.649972 180)
			(size 0.450088 0.450088)
			(layers "F.Cu" "F.Mask" "F.Paste")
			(net "M_D_CPU1_RESET_N")
		)
		(pad "AU60" smd circle
			(at 20.359878 -7.649972 180)
			(size 0.450088 0.450088)
			(layers "F.Cu" "F.Mask" "F.Paste")
			(net "Net_2016")
		)
		(pad "AU61" smd circle
			(at 21.299932 -7.649972 180)
			(size 0.450088 0.450088)
			(layers "F.Cu" "F.Mask" "F.Paste")
			(net "GND")
		)
		(pad "AU62" smd circle
			(at 22.239986 -7.649972 180)
			(size 0.450088 0.450088)
			(layers "F.Cu" "F.Mask" "F.Paste")
			(net "M_B_CPU1_RESET_N")
		)
		(pad "AU63" smd circle
			(at 23.18004 -7.649972 180)
			(size 0.450088 0.450088)
			(layers "F.Cu" "F.Mask" "F.Paste")
			(net "GND")
		)
		(pad "AU64" smd circle
			(at 24.120094 -7.649972 180)
			(size 0.450088 0.450088)
			(layers "F.Cu" "F.Mask" "F.Paste")
			(net "Net_2000")
		)
		(pad "AU65" smd circle
			(at 25.059894 -7.649972 180)
			(size 0.450088 0.450088)
			(layers "F.Cu" "F.Mask" "F.Paste")
			(net "GND")
		)
		(pad "AU66" smd circle
			(at 25.999948 -7.649972 180)
			(size 0.450088 0.450088)
			(layers "F.Cu" "F.Mask" "F.Paste")
			(net "M_F_CPU1_RESET_N")
		)
		(pad "AU67" smd circle
			(at 26.940002 -7.649972 180)
			(size 0.450088 0.450088)
			(layers "F.Cu" "F.Mask" "F.Paste")
			(net "Net_2032")
		)
		(pad "AU68" smd circle
			(at 27.880056 -7.649972 180)
			(size 0.450088 0.450088)
			(layers "F.Cu" "F.Mask" "F.Paste")
			(net "GND")
		)
		(pad "AU69" smd circle
			(at 28.82011 -7.649972 180)
			(size 0.450088 0.450088)
			(layers "F.Cu" "F.Mask" "F.Paste")
			(net "M_E_CPU1_RESET_N")
		)
		(pad "AU70" smd circle
			(at 29.75991 -7.649972 180)
			(size 0.450088 0.450088)
			(layers "F.Cu" "F.Mask" "F.Paste")
			(net "GND")
		)
		(pad "AU71" smd circle
			(at 30.699964 -7.649972 180)
			(size 0.450088 0.450088)
			(layers "F.Cu" "F.Mask" "F.Paste")
			(net "Net_2024")
		)
		(pad "AU72" smd circle
			(at 31.640018 -7.649972 180)
			(size 0.450088 0.450088)
			(layers "F.Cu" "F.Mask" "F.Paste")
			(net "GND")
		)
		(pad "AU73" smd circle
			(at 32.580072 -7.649972 180)
			(size 0.450088 0.450088)
			(layers "F.Cu" "F.Mask" "F.Paste")
			(net "GND")
		)
		(pad "AU74" smd circle
			(at 33.519872 -7.649972 180)
			(size 0.450088 0.450088)
			(layers "F.Cu" "F.Mask" "F.Paste")
			(net "Net_1992")
		)
		(pad "AU75" smd circle
			(at 34.459926 -7.649972 180)
			(size 0.450088 0.450088)
			(layers "F.Cu" "F.Mask" "F.Paste")
			(net "GND")
		)
		(pad "AV2" smd circle
			(at -33.690052 -6.839966 180)
			(size 0.450088 0.450088)
			(layers "F.Cu" "F.Mask" "F.Paste")
			(net "Net_2040")
		)
		(pad "AV3" smd circle
			(at -32.749998 -6.839966 180)
			(size 0.450088 0.450088)
			(layers "F.Cu" "F.Mask" "F.Paste")
			(net "GND")
		)
		(pad "AV4" smd circle
			(at -31.809944 -6.839966 180)
			(size 0.450088 0.450088)
			(layers "F.Cu" "F.Mask" "F.Paste")
			(net "M_G_CPU1_SA_CS_N<1>")
		)
		(pad "AV5" smd circle
			(at -30.86989 -6.839966 180)
			(size 0.450088 0.450088)
			(layers "F.Cu" "F.Mask" "F.Paste")
			(net "PVDDCR_SOC_P1")
		)
		(pad "AV6" smd circle
			(at -29.93009 -6.839966 180)
			(size 0.450088 0.450088)
			(layers "F.Cu" "F.Mask" "F.Paste")
			(net "Net_2189")
		)
		(pad "AV7" smd circle
			(at -28.990036 -6.839966 180)
			(size 0.450088 0.450088)
			(layers "F.Cu" "F.Mask" "F.Paste")
			(net "M_K_CPU1_SA_CS_N<1>")
		)
		(pad "AV8" smd circle
			(at -28.049982 -6.839966 180)
			(size 0.450088 0.450088)
			(layers "F.Cu" "F.Mask" "F.Paste")
			(net "GND")
		)
		(pad "AV9" smd circle
			(at -27.109928 -6.839966 180)
			(size 0.450088 0.450088)
			(layers "F.Cu" "F.Mask" "F.Paste")
			(net "Net_2181")
		)
		(pad "AV10" smd circle
			(at -26.170128 -6.839966 180)
			(size 0.450088 0.450088)
			(layers "F.Cu" "F.Mask" "F.Paste")
			(net "GND")
		)
		(pad "AV11" smd circle
			(at -25.230074 -6.839966 180)
			(size 0.450088 0.450088)
			(layers "F.Cu" "F.Mask" "F.Paste")
			(net "M_L_CPU1_SA_CS_N<1>")
		)
		(pad "AV12" smd circle
			(at -24.29002 -6.839966 180)
			(size 0.450088 0.450088)
			(layers "F.Cu" "F.Mask" "F.Paste")
			(net "PVDDCR_SOC_P1")
		)
		(pad "AV13" smd circle
			(at -23.349966 -6.839966 180)
			(size 0.450088 0.450088)
			(layers "F.Cu" "F.Mask" "F.Paste")
			(net "Net_2048")
		)
		(pad "AV14" smd circle
			(at -22.409912 -6.839966 180)
			(size 0.450088 0.450088)
			(layers "F.Cu" "F.Mask" "F.Paste")
			(net "M_H_CPU1_SA_CS_N<1>")
		)
		(pad "AV15" smd circle
			(at -21.470112 -6.839966 180)
			(size 0.450088 0.450088)
			(layers "F.Cu" "F.Mask" "F.Paste")
			(net "GND")
		)
		(pad "AV16" smd circle
			(at -20.530058 -6.839966 180)
			(size 0.450088 0.450088)
			(layers "F.Cu" "F.Mask" "F.Paste")
			(net "Net_2064")
		)
		(pad "AV17" smd circle
			(at -19.590004 -6.839966 180)
			(size 0.450088 0.450088)
			(layers "F.Cu" "F.Mask" "F.Paste")
			(net "GND")
		)
		(pad "AV18" smd circle
			(at -18.64995 -6.839966 180)
			(size 0.450088 0.450088)
			(layers "F.Cu" "F.Mask" "F.Paste")
			(net "M_J_CPU1_SA_CS_N<1>")
		)
		(pad "AV19" smd circle
			(at -17.709896 -6.839966 180)
			(size 0.450088 0.450088)
			(layers "F.Cu" "F.Mask" "F.Paste")
			(net "PVDDCR_SOC_P1")
		)
		(pad "AV20" smd circle
			(at -16.770096 -6.839966 180)
			(size 0.450088 0.450088)
			(layers "F.Cu" "F.Mask" "F.Paste")
			(net "Net_2056")
		)
		(pad "AV21" smd circle
			(at -15.830042 -6.839966 180)
			(size 0.450088 0.450088)
			(layers "F.Cu" "F.Mask" "F.Paste")
			(net "M_I_CPU1_SA_CS_N<1>")
		)
		(pad "AV22" smd circle
			(at -14.889988 -6.839966 180)
			(size 0.450088 0.450088)
			(layers "F.Cu" "F.Mask" "F.Paste")
			(net "PVDDCR_SOC_P1")
		)
		(pad "AV23" smd circle
			(at -13.949934 -6.839966 180)
			(size 0.450088 0.450088)
			(layers "F.Cu" "F.Mask" "F.Paste")
			(net "GND")
		)
		(pad "AV24" smd circle
			(at -13.00988 -6.839966 180)
			(size 0.450088 0.450088)
			(layers "F.Cu" "F.Mask" "F.Paste")
			(net "PVDDCR_SOC_P1")
		)
		(pad "AV25" smd circle
			(at -12.07008 -6.839966 180)
			(size 0.450088 0.450088)
			(layers "F.Cu" "F.Mask" "F.Paste")
			(net "GND")
		)
		(pad "AV26" smd circle
			(at -11.130026 -6.839966 180)
			(size 0.450088 0.450088)
			(layers "F.Cu" "F.Mask" "F.Paste")
			(net "PVDDCR_SOC_P1")
		)
		(pad "AV27" smd circle
			(at -10.189972 -6.839966 180)
			(size 0.450088 0.450088)
			(layers "F.Cu" "F.Mask" "F.Paste")
			(net "GND")
		)
		(pad "AV28" smd circle
			(at -9.249918 -6.839966 180)
			(size 0.450088 0.450088)
			(layers "F.Cu" "F.Mask" "F.Paste")
			(net "PVDDCR_SOC_P1")
		)
	)
)
